(kicad_pcb
	(version 20241229)
	(generator "pcbnew")
	(generator_version "9.0")
	(general
		(thickness 1.61)
		(legacy_teardrops no)
	)
	(paper "A3")
	(title_block
		(title "RDIMM DDR5 Tester")
		(date "2026-05-21")
		(rev "2.2.0")
		(company "Antmicro")
		(comment 9 "footprints 673-677 of 796")
	)
	(layers
		(0 "F.Cu" signal)
		(4 "In1.Cu" power)
		(6 "In2.Cu" mixed)
		(8 "In3.Cu" power)
		(10 "In4.Cu" mixed)
		(12 "In5.Cu" power)
		(14 "In6.Cu" mixed)
		(16 "In7.Cu" power)
		(18 "In8.Cu" power)
		(20 "In9.Cu" mixed)
		(22 "In10.Cu" power)
		(2 "B.Cu" signal)
		(9 "F.Adhes" user "F.Adhesive")
		(11 "B.Adhes" user "B.Adhesive")
		(13 "F.Paste" user)
		(15 "B.Paste" user)
		(5 "F.SilkS" user "F.Silkscreen")
		(7 "B.SilkS" user "B.Silkscreen")
		(1 "F.Mask" user)
		(3 "B.Mask" user)
		(17 "Dwgs.User" user "User.Drawings")
		(19 "Cmts.User" user "User.Comments")
		(21 "Eco1.User" user "User.Eco1")
		(23 "Eco2.User" user "User.Eco2")
		(25 "Edge.Cuts" user)
		(27 "Margin" user)
		(31 "F.CrtYd" user "F.Courtyard")
		(29 "B.CrtYd" user "B.Courtyard")
		(35 "F.Fab" user)
		(33 "B.Fab" user)
	)
	(footprint "antmicro-footprints:C_0402_1005Metric_EIA"
		(layer "B.Cu")
		(at 197.5 145 180)
		(descr "Capacitor SMD 0402 (1005 Metric), square (rectangular) end terminal, IPC_7351 nominal, (Body size source: IPC-SM-782 page 76, https://www.pcb-3d.com/wordpress/wp-content/uploads/ipc-sm-782a_amendment_1_and_2.pdf)")
		(tags "capacitor 0402")
		(property "Reference" "C60"
			(at -3.05 -0.425 0)
			(layer "B.SilkS")
			(effects
				(font
					(size 0.7 0.7)
					(thickness 0.15)
				)
				(justify left bottom mirror)
			)
		)
		(property "Value" "C_100n_0402"
			(at 0 -1.169 0)
			(layer "B.Fab")
			(effects
				(font
					(size 0.7 0.7)
					(thickness 0.15)
				)
				(justify left bottom mirror)
			)
		)
		(property "Datasheet" "https://www.murata.com/products/productdetail?partno=GRM155R61H104KE14%23"
			(at 0 0 180)
			(layer "F.Fab")
			(hide yes)
			(effects
				(font
					(size 1.27 1.27)
					(thickness 0.15)
				)
			)
		)
		(property "MPN" "GRM155R61H104KE14D"
			(at 0 0 180)
			(unlocked yes)
			(layer "B.Fab")
			(hide yes)
			(effects
				(font
					(size 1 1)
					(thickness 0.15)
				)
				(justify mirror)
			)
		)
		(property "Manufacturer" "Murata"
			(at 0 0 180)
			(unlocked yes)
			(layer "B.Fab")
			(hide yes)
			(effects
				(font
					(size 1 1)
					(thickness 0.15)
				)
				(justify mirror)
			)
		)
		(property "License" "Apache-2.0"
			(at 0 0 180)
			(unlocked yes)
			(layer "B.Fab")
			(hide yes)
			(effects
				(font
					(size 1 1)
					(thickness 0.15)
				)
				(justify mirror)
			)
		)
		(property "Author" "Antmicro"
			(at 0 0 180)
			(unlocked yes)
			(layer "B.Fab")
			(hide yes)
			(effects
				(font
					(size 1 1)
					(thickness 0.15)
				)
				(justify mirror)
			)
		)
		(property "Val" "100n"
			(at 0 0 180)
			(unlocked yes)
			(layer "B.Fab")
			(hide yes)
			(effects
				(font
					(size 1 1)
					(thickness 0.15)
				)
				(justify mirror)
			)
		)
		(property "Voltage" "50V"
			(at 0 0 180)
			(unlocked yes)
			(layer "B.Fab")
			(hide yes)
			(effects
				(font
					(size 1 1)
					(thickness 0.15)
				)
				(justify mirror)
			)
		)
		(property "Dielectric" "X5R"
			(at 0 0 180)
			(unlocked yes)
			(layer "B.Fab")
			(hide yes)
			(effects
				(font
					(size 1 1)
					(thickness 0.15)
				)
				(justify mirror)
			)
		)
		(sheetname "/FPGA power/")
		(sheetfile "fpga-power.kicad_sch")
		(attr smd)
		(fp_rect
			(start -0.95 0.45)
			(end 0.95 -0.45)
			(stroke
				(width 0.05)
				(type default)
			)
			(fill no)
			(layer "B.CrtYd")
		)
		(fp_line
			(start 0.498 0.25)
			(end 0.498 -0.248)
			(stroke
				(width 0.15)
				(type solid)
			)
			(layer "B.Fab")
		)
		(fp_line
			(start 0.498 -0.248)
			(end -0.5 -0.248)
			(stroke
				(width 0.15)
				(type solid)
			)
			(layer "B.Fab")
		)
		(fp_line
			(start -0.5 0.25)
			(end 0.498 0.25)
			(stroke
				(width 0.15)
				(type solid)
			)
			(layer "B.Fab")
		)
		(fp_line
			(start -0.5 -0.248)
			(end -0.5 0.25)
			(stroke
				(width 0.15)
				(type solid)
			)
			(layer "B.Fab")
		)
		(fp_text user "License: Apache-2.0"
			(at -0.9656 -4.369 0)
			(layer "B.Fab")
			(effects
				(font
					(size 0.7 0.7)
					(thickness 0.15)
				)
				(justify left bottom mirror)
			)
		)
		(fp_text user "${REFERENCE}"
			(at -0.9656 -3.169 0)
			(layer "B.Fab")
			(effects
				(font
					(size 0.7 0.7)
					(thickness 0.15)
				)
				(justify left bottom mirror)
			)
		)
		(fp_text user "Author: Antmicro"
			(at -0.9656 -5.569 0)
			(layer "B.Fab")
			(effects
				(font
					(size 0.7 0.7)
					(thickness 0.15)
				)
				(justify left bottom mirror)
			)
		)
		(pad "1" smd roundrect
			(at -0.5 0 90)
			(size 0.6 0.6)
			(layers "B.Cu" "B.Mask" "B.Paste")
			(roundrect_rratio 0.25)
			(net 1 "GND")
			(pintype "passive")
		)
		(pad "2" smd roundrect
			(at 0.498 0 180)
			(size 0.6 0.6)
			(layers "B.Cu" "B.Mask" "B.Paste")
			(roundrect_rratio 0.25)
			(net 687 "VDDQ")
			(pintype "passive")
		)
	)
	(footprint "antmicro-footprints:C_0402_1005Metric_EIA"
		(layer "B.Cu")
		(at 191 156.5 -90)
		(descr "Capacitor SMD 0402 (1005 Metric), square (rectangular) end terminal, IPC_7351 nominal, (Body size source: IPC-SM-782 page 76, https://www.pcb-3d.com/wordpress/wp-content/uploads/ipc-sm-782a_amendment_1_and_2.pdf)")
		(tags "capacitor 0402")
		(property "Reference" "C67"
			(at -12.15 30.7 90)
			(layer "B.SilkS")
			(effects
				(font
					(size 0.7 0.7)
					(thickness 0.15)
				)
				(justify left bottom mirror)
			)
		)
		(property "Value" "C_10u_10V_0402"
			(at 0 -1.169 90)
			(layer "B.Fab")
			(effects
				(font
					(size 0.7 0.7)
					(thickness 0.15)
				)
				(justify left bottom mirror)
			)
		)
		(property "Datasheet" "https://www.murata.com/products/productdetail?partno=GRM155R61A106ME11%23"
			(at 0 0 270)
			(layer "F.Fab")
			(hide yes)
			(effects
				(font
					(size 1.27 1.27)
					(thickness 0.15)
				)
			)
		)
		(property "MPN" "GRM155R61A106ME11D"
			(at 0 0 270)
			(unlocked yes)
			(layer "B.Fab")
			(hide yes)
			(effects
				(font
					(size 1 1)
					(thickness 0.15)
				)
				(justify mirror)
			)
		)
		(property "Manufacturer" "Murata"
			(at 0 0 270)
			(unlocked yes)
			(layer "B.Fab")
			(hide yes)
			(effects
				(font
					(size 1 1)
					(thickness 0.15)
				)
				(justify mirror)
			)
		)
		(property "License" "Apache-2.0"
			(at 0 0 270)
			(unlocked yes)
			(layer "B.Fab")
			(hide yes)
			(effects
				(font
					(size 1 1)
					(thickness 0.15)
				)
				(justify mirror)
			)
		)
		(property "Author" "Antmicro"
			(at 0 0 270)
			(unlocked yes)
			(layer "B.Fab")
			(hide yes)
			(effects
				(font
					(size 1 1)
					(thickness 0.15)
				)
				(justify mirror)
			)
		)
		(property "Val" "10u"
			(at 0 0 270)
			(unlocked yes)
			(layer "B.Fab")
			(hide yes)
			(effects
				(font
					(size 1 1)
					(thickness 0.15)
				)
				(justify mirror)
			)
		)
		(property "Voltage" "10V"
			(at 0 0 270)
			(unlocked yes)
			(layer "B.Fab")
			(hide yes)
			(effects
				(font
					(size 1 1)
					(thickness 0.15)
				)
				(justify mirror)
			)
		)
		(property "Dielectric" "X5R"
			(at 0 0 270)
			(unlocked yes)
			(layer "B.Fab")
			(hide yes)
			(effects
				(font
					(size 1 1)
					(thickness 0.15)
				)
				(justify mirror)
			)
		)
		(sheetname "/FPGA power/")
		(sheetfile "fpga-power.kicad_sch")
		(attr smd)
		(fp_rect
			(start -0.95 0.45)
			(end 0.95 -0.45)
			(stroke
				(width 0.05)
				(type default)
			)
			(fill no)
			(layer "B.CrtYd")
		)
		(fp_line
			(start -0.5 0.25)
			(end 0.498 0.25)
			(stroke
				(width 0.15)
				(type solid)
			)
			(layer "B.Fab")
		)
		(fp_line
			(start 0.498 0.25)
			(end 0.498 -0.248)
			(stroke
				(width 0.15)
				(type solid)
			)
			(layer "B.Fab")
		)
		(fp_line
			(start -0.5 -0.248)
			(end -0.5 0.25)
			(stroke
				(width 0.15)
				(type solid)
			)
			(layer "B.Fab")
		)
		(fp_line
			(start 0.498 -0.248)
			(end -0.5 -0.248)
			(stroke
				(width 0.15)
				(type solid)
			)
			(layer "B.Fab")
		)
		(fp_text user "License: Apache-2.0"
			(at -0.9656 -4.369 90)
			(layer "B.Fab")
			(effects
				(font
					(size 0.7 0.7)
					(thickness 0.15)
				)
				(justify left bottom mirror)
			)
		)
		(fp_text user "Author: Antmicro"
			(at -0.9656 -5.569 90)
			(layer "B.Fab")
			(effects
				(font
					(size 0.7 0.7)
					(thickness 0.15)
				)
				(justify left bottom mirror)
			)
		)
		(fp_text user "${REFERENCE}"
			(at -0.9656 -3.169 90)
			(layer "B.Fab")
			(effects
				(font
					(size 0.7 0.7)
					(thickness 0.15)
				)
				(justify left bottom mirror)
			)
		)
		(pad "1" smd roundrect
			(at -0.5 0 180)
			(size 0.6 0.6)
			(layers "B.Cu" "B.Mask" "B.Paste")
			(roundrect_rratio 0.25)
			(net 1 "GND")
			(pintype "passive")
		)
		(pad "2" smd roundrect
			(at 0.498 0 270)
			(size 0.6 0.6)
			(layers "B.Cu" "B.Mask" "B.Paste")
			(roundrect_rratio 0.25)
			(net 553 "+0V85")
			(pintype "passive")
		)
	)
	(footprint "antmicro-footprints:C_0402_1005Metric"
		(layer "B.Cu")
		(at 204.75 138.5245 90)
		(descr "Capacitor SMD 0402")
		(tags "capacitor SMD 0402")
		(property "Reference" "C332"
			(at -2.3755 -0.15 90)
			(layer "B.SilkS")
			(effects
				(font
					(size 0.7 0.7)
					(thickness 0.15)
				)
				(justify mirror)
			)
		)
		(property "Value" "C_100n_0402"
			(at -1.022927 -2.155213 90)
			(layer "B.Fab")
			(effects
				(font
					(size 0.7 0.7)
					(thickness 0.15)
				)
				(justify right top mirror)
			)
		)
		(property "Datasheet" "https://www.murata.com/products/productdetail?partno=GRM155R61H104KE14%23"
			(at 0 0 90)
			(layer "B.Fab")
			(hide yes)
			(effects
				(font
					(size 1.27 1.27)
					(thickness 0.15)
				)
				(justify mirror)
			)
		)
		(property "Manufacturer" "Murata"
			(at 0 0 270)
			(unlocked yes)
			(layer "B.Fab")
			(hide yes)
			(effects
				(font
					(size 1 1)
					(thickness 0.15)
				)
				(justify mirror)
			)
		)
		(property "MPN" "GRM155R61H104KE14D"
			(at 0 0 270)
			(unlocked yes)
			(layer "B.Fab")
			(hide yes)
			(effects
				(font
					(size 1 1)
					(thickness 0.15)
				)
				(justify mirror)
			)
		)
		(property "Val" "100n"
			(at 0 0 270)
			(unlocked yes)
			(layer "B.Fab")
			(hide yes)
			(effects
				(font
					(size 1 1)
					(thickness 0.15)
				)
				(justify mirror)
			)
		)
		(property "License" "Apache-2.0"
			(at 0 0 270)
			(unlocked yes)
			(layer "B.Fab")
			(hide yes)
			(effects
				(font
					(size 1 1)
					(thickness 0.15)
				)
				(justify mirror)
			)
		)
		(property "Author" "Antmicro"
			(at 0 0 270)
			(unlocked yes)
			(layer "B.Fab")
			(hide yes)
			(effects
				(font
					(size 1 1)
					(thickness 0.15)
				)
				(justify mirror)
			)
		)
		(property "Voltage" "50V"
			(at 0 0 270)
			(unlocked yes)
			(layer "B.Fab")
			(hide yes)
			(effects
				(font
					(size 1 1)
					(thickness 0.15)
				)
				(justify mirror)
			)
		)
		(property "Dielectric" "X5R"
			(at 0 0 270)
			(unlocked yes)
			(layer "B.Fab")
			(hide yes)
			(effects
				(font
					(size 1 1)
					(thickness 0.15)
				)
				(justify mirror)
			)
		)
		(sheetname "/Supply/")
		(sheetfile "supply.kicad_sch")
		(attr smd)
		(fp_rect
			(start -0.925 0.47)
			(end 0.925 -0.47)
			(stroke
				(width 0.05)
				(type default)
			)
			(fill no)
			(layer "B.CrtYd")
		)
		(fp_line
			(start 0.504 -0.248)
			(end -0.494 -0.248)
			(stroke
				(width 0.15)
				(type solid)
			)
			(layer "B.Fab")
		)
		(fp_line
			(start -0.494 -0.248)
			(end -0.494 0.25)
			(stroke
				(width 0.15)
				(type solid)
			)
			(layer "B.Fab")
		)
		(fp_line
			(start 0.504 0.25)
			(end 0.504 -0.248)
			(stroke
				(width 0.15)
				(type solid)
			)
			(layer "B.Fab")
		)
		(fp_line
			(start -0.494 0.25)
			(end 0.504 0.25)
			(stroke
				(width 0.15)
				(type solid)
			)
			(layer "B.Fab")
		)
		(fp_text user "${REFERENCE}"
			(at -0.939 -4.599 90)
			(layer "B.Fab")
			(effects
				(font
					(size 0.7 0.7)
					(thickness 0.15)
				)
				(justify right top mirror)
			)
		)
		(fp_text user "License: Apache-2.0"
			(at -0.939 -5.799 90)
			(layer "B.Fab")
			(effects
				(font
					(size 0.7 0.7)
					(thickness 0.15)
				)
				(justify right top mirror)
			)
		)
		(fp_text user "Author: Antmicro"
			(at -0.939 -3.399 90)
			(layer "B.Fab")
			(effects
				(font
					(size 0.7 0.7)
					(thickness 0.15)
				)
				(justify right top mirror)
			)
		)
		(pad "1" smd roundrect
			(at -0.48 0 90)
			(size 0.59 0.64)
			(layers "B.Cu" "B.Mask" "B.Paste")
			(roundrect_rratio 0.25)
			(net 1 "GND")
			(pintype "passive")
		)
		(pad "2" smd roundrect
			(at 0.48 0 90)
			(size 0.59 0.64)
			(layers "B.Cu" "B.Mask" "B.Paste")
			(roundrect_rratio 0.25)
			(net 825 "DAC_VREF")
			(pintype "passive")
		)
	)
	(footprint "antmicro-footprints:C_0402_1005Metric_EIA"
		(layer "B.Cu")
		(at 181.5 150)
		(descr "Capacitor SMD 0402 (1005 Metric), square (rectangular) end terminal, IPC_7351 nominal, (Body size source: IPC-SM-782 page 76, https://www.pcb-3d.com/wordpress/wp-content/uploads/ipc-sm-782a_amendment_1_and_2.pdf)")
		(tags "capacitor 0402")
		(property "Reference" "C23"
			(at -32.125 -10.325 0)
			(layer "B.SilkS")
			(effects
				(font
					(size 0.7 0.7)
					(thickness 0.15)
				)
				(justify right bottom mirror)
			)
		)
		(property "Value" "C_10u_10V_0402"
			(at 0 -1.169 0)
			(layer "B.Fab")
			(effects
				(font
					(size 0.7 0.7)
					(thickness 0.15)
				)
				(justify right bottom mirror)
			)
		)
		(property "Datasheet" "https://www.murata.com/products/productdetail?partno=GRM155R61A106ME11%23"
			(at 0 0 0)
			(layer "F.Fab")
			(hide yes)
			(effects
				(font
					(size 1.27 1.27)
					(thickness 0.15)
				)
			)
		)
		(property "MPN" "GRM155R61A106ME11D"
			(at 0 0 0)
			(unlocked yes)
			(layer "B.Fab")
			(hide yes)
			(effects
				(font
					(size 1 1)
					(thickness 0.15)
				)
				(justify mirror)
			)
		)
		(property "Manufacturer" "Murata"
			(at 0 0 0)
			(unlocked yes)
			(layer "B.Fab")
			(hide yes)
			(effects
				(font
					(size 1 1)
					(thickness 0.15)
				)
				(justify mirror)
			)
		)
		(property "License" "Apache-2.0"
			(at 0 0 0)
			(unlocked yes)
			(layer "B.Fab")
			(hide yes)
			(effects
				(font
					(size 1 1)
					(thickness 0.15)
				)
				(justify mirror)
			)
		)
		(property "Author" "Antmicro"
			(at 0 0 0)
			(unlocked yes)
			(layer "B.Fab")
			(hide yes)
			(effects
				(font
					(size 1 1)
					(thickness 0.15)
				)
				(justify mirror)
			)
		)
		(property "Val" "10u"
			(at 0 0 0)
			(unlocked yes)
			(layer "B.Fab")
			(hide yes)
			(effects
				(font
					(size 1 1)
					(thickness 0.15)
				)
				(justify mirror)
			)
		)
		(property "Voltage" "10V"
			(at 0 0 0)
			(unlocked yes)
			(layer "B.Fab")
			(hide yes)
			(effects
				(font
					(size 1 1)
					(thickness 0.15)
				)
				(justify mirror)
			)
		)
		(property "Dielectric" "X5R"
			(at 0 0 0)
			(unlocked yes)
			(layer "B.Fab")
			(hide yes)
			(effects
				(font
					(size 1 1)
					(thickness 0.15)
				)
				(justify mirror)
			)
		)
		(sheetname "/FPGA power/")
		(sheetfile "fpga-power.kicad_sch")
		(attr smd)
		(fp_rect
			(start -0.95 0.45)
			(end 0.95 -0.45)
			(stroke
				(width 0.05)
				(type default)
			)
			(fill no)
			(layer "B.CrtYd")
		)
		(fp_line
			(start -0.5 -0.248)
			(end -0.5 0.25)
			(stroke
				(width 0.15)
				(type solid)
			)
			(layer "B.Fab")
		)
		(fp_line
			(start -0.5 0.25)
			(end 0.498 0.25)
			(stroke
				(width 0.15)
				(type solid)
			)
			(layer "B.Fab")
		)
		(fp_line
			(start 0.498 -0.248)
			(end -0.5 -0.248)
			(stroke
				(width 0.15)
				(type solid)
			)
			(layer "B.Fab")
		)
		(fp_line
			(start 0.498 0.25)
			(end 0.498 -0.248)
			(stroke
				(width 0.15)
				(type solid)
			)
			(layer "B.Fab")
		)
		(fp_text user "Author: Antmicro"
			(at -0.9656 -5.569 180)
			(layer "B.Fab")
			(effects
				(font
					(size 0.7 0.7)
					(thickness 0.15)
				)
				(justify left bottom mirror)
			)
		)
		(fp_text user "${REFERENCE}"
			(at -0.9656 -3.169 180)
			(layer "B.Fab")
			(effects
				(font
					(size 0.7 0.7)
					(thickness 0.15)
				)
				(justify left bottom mirror)
			)
		)
		(fp_text user "License: Apache-2.0"
			(at -0.9656 -4.369 180)
			(layer "B.Fab")
			(effects
				(font
					(size 0.7 0.7)
					(thickness 0.15)
				)
				(justify left bottom mirror)
			)
		)
		(pad "1" smd roundrect
			(at -0.5 0 270)
			(size 0.6 0.6)
			(layers "B.Cu" "B.Mask" "B.Paste")
			(roundrect_rratio 0.25)
			(net 1 "GND")
			(pintype "passive")
		)
		(pad "2" smd roundrect
			(at 0.498 0)
			(size 0.6 0.6)
			(layers "B.Cu" "B.Mask" "B.Paste")
			(roundrect_rratio 0.25)
			(net 151 "+3V3")
			(pintype "passive")
		)
	)
	(footprint "antmicro-footprints:R_0402_1005Metric"
		(layer "B.Cu")
		(at 238.424499 186.849 180)
		(descr "Resistor SMD 0402")
		(tags "resistor SMD 0402")
		(property "Reference" "R175"
			(at -3.95 -0.5 0)
			(layer "B.SilkS")
			(effects
				(font
					(size 0.7 0.7)
					(thickness 0.15)
				)
				(justify left bottom mirror)
			)
		)
		(property "Value" "R_0R_0402"
			(at -1.011843 -1.772047 0)
			(layer "B.Fab")
			(effects
				(font
					(size 0.7 0.7)
					(thickness 0.15)
				)
				(justify left bottom mirror)
			)
		)
		(property "Datasheet" "https://industrial.panasonic.com/cdbs/www-data/pdf/RDA0000/AOA0000C301.pdf"
			(at 0 0 180)
			(layer "F.Fab")
			(hide yes)
			(effects
				(font
					(size 1.27 1.27)
					(thickness 0.15)
				)
			)
		)
		(property "Manufacturer" "Panasonic"
			(at 0 0 180)
			(unlocked yes)
			(layer "B.Fab")
			(hide yes)
			(effects
				(font
					(size 1 1)
					(thickness 0.15)
				)
				(justify mirror)
			)
		)
		(property "MPN" "ERJ2GE0R00X"
			(at 0 0 180)
			(unlocked yes)
			(layer "B.Fab")
			(hide yes)
			(effects
				(font
					(size 1 1)
					(thickness 0.15)
				)
				(justify mirror)
			)
		)
		(property "Val" "0R"
			(at 0 0 180)
			(unlocked yes)
			(layer "B.Fab")
			(hide yes)
			(effects
				(font
					(size 1 1)
					(thickness 0.15)
				)
				(justify mirror)
			)
		)
		(property "License" "Apache-2.0"
			(at 0 0 180)
			(unlocked yes)
			(layer "B.Fab")
			(hide yes)
			(effects
				(font
					(size 1 1)
					(thickness 0.15)
				)
				(justify mirror)
			)
		)
		(property "Author" "Antmicro"
			(at 0 0 180)
			(unlocked yes)
			(layer "B.Fab")
			(hide yes)
			(effects
				(font
					(size 1 1)
					(thickness 0.15)
				)
				(justify mirror)
			)
		)
		(property "Tolerance" "~"
			(at 0 0 180)
			(unlocked yes)
			(layer "B.Fab")
			(hide yes)
			(effects
				(font
					(size 1 1)
					(thickness 0.15)
				)
				(justify mirror)
			)
		)
		(property "Current" "1A"
			(at 0 0 180)
			(unlocked yes)
			(layer "B.Fab")
			(hide yes)
			(effects
				(font
					(size 1 1)
					(thickness 0.15)
				)
				(justify mirror)
			)
		)
		(sheetname "/I^{2}C + I3C/")
		(sheetfile "i2c.kicad_sch")
		(attr smd exclude_from_bom dnp)
		(fp_rect
			(start -0.925 0.47)
			(end 0.925 -0.47)
			(stroke
				(width 0.05)
				(type default)
			)
			(fill no)
			(layer "B.CrtYd")
		)
		(fp_rect
			(start -0.5 0.25)
			(end 0.5 -0.25)
			(stroke
				(width 0.15)
				(type solid)
			)
			(fill no)
			(layer "B.Fab")
		)
		(fp_text user "Author: Antmicro"
			(at -0.95 -4.169 0)
			(layer "B.Fab")
			(effects
				(font
					(size 0.7 0.7)
					(thickness 0.15)
				)
				(justify left bottom mirror)
			)
		)
		(fp_text user "${REFERENCE}"
			(at -0.95 -3.168 0)
			(layer "B.Fab")
			(effects
				(font
					(size 0.7 0.7)
					(thickness 0.15)
				)
				(justify left bottom mirror)
			)
		)
		(fp_text user "License: Apache-2.0"
			(at -0.95 -5.169 0)
			(layer "B.Fab")
			(effects
				(font
					(size 0.7 0.7)
					(thickness 0.15)
				)
				(justify left bottom mirror)
			)
		)
		(pad "1" smd roundrect
			(at -0.48 0 180)
			(size 0.59 0.64)
			(layers "B.Cu" "B.Mask" "B.Paste")
			(roundrect_rratio 0.25)
			(net 533 "/I^{2}C + I3C/PWR.SDA")
			(pintype "passive")
		)
		(pad "2" smd roundrect
			(at 0.48 0 180)
			(size 0.59 0.64)
			(layers "B.Cu" "B.Mask" "B.Paste")
			(roundrect_rratio 0.25)
			(net 746 "/FPGA Config/FPGA_PWR.SDA")
			(pintype "passive")
		)
	)
)
